(kicad_pcb
	(version 20260206)
	(generator "pcbnew")
	(generator_version "10.0")
	(general
		(thickness 1.6)
		(legacy_teardrops no)
	)
	(paper "A4")
	(title_block
		(title "03242023_DA0F0TMBIJ0_F0T_Motherboard_J_brd_V01_OCP.brd")
		(comment 1 "Grand Teton / footprints 3196-3197 of 6105")
	)
	(layers
		(0 "F.Cu" signal "TOP")
		(4 "In1.Cu" signal "GND")
		(6 "In2.Cu" signal "IN1")
		(8 "In3.Cu" signal "GND1")
		(10 "In4.Cu" signal "IN2")
		(12 "In5.Cu" signal "GND2")
		(14 "In6.Cu" signal "IN3")
		(16 "In7.Cu" signal "GND3")
		(18 "In8.Cu" signal "VCC")
		(20 "In9.Cu" signal "VCC1")
		(22 "In10.Cu" signal "GND4")
		(24 "In11.Cu" signal "IN4")
		(26 "In12.Cu" signal "GND5")
		(28 "In13.Cu" signal "IN5")
		(30 "In14.Cu" signal "GND6")
		(32 "In15.Cu" signal "IN6")
		(34 "In16.Cu" signal "GND7")
		(2 "B.Cu" signal "BOTTOM")
		(9 "F.Adhes" user "F.Adhesive")
		(11 "B.Adhes" user "B.Adhesive")
		(13 "F.Paste" user "Package Geometry/Pastemask Top")
		(15 "B.Paste" user "Package Geometry/Pastemask Bottom")
		(5 "F.SilkS" user "Ref Des/Silkscreen Top")
		(7 "B.SilkS" user "Ref Des/Silkscreen Bottom")
		(1 "F.Mask" user "Board Geometry/Soldermask Top")
		(3 "B.Mask" user "Board Geometry/Soldermask Bottom")
		(17 "Dwgs.User" user "User.Drawings")
		(19 "Cmts.User" user "User.Comments")
		(21 "Eco1.User" user "User.Eco1")
		(23 "Eco2.User" user "User.Eco2")
		(25 "Edge.Cuts" user "Board Geometry/Outline")
		(27 "Margin" user)
		(31 "F.CrtYd" user "Package Geometry/Place Bound Top")
		(29 "B.CrtYd" user "Package Geometry/Place Bound Bottom")
		(35 "F.Fab" user "Ref Des/Assembly Top")
		(33 "B.Fab" user "Ref Des/Assembly Bottom")
	)
	(footprint ""
		(layer "F.Cu")
		(at 75.546458 -20.950682 180)
		(property "Reference" "PR3821"
			(at 0 0 180)
			(layer "F.SilkS")
			(hide yes)
			(effects
				(font
					(size 1.27 1.27)
				)
			)
		)
		(property "Value" ""
			(at 0 0 180)
			(layer "F.Fab")
			(effects
				(font
					(size 1.27 1.27)
				)
			)
		)
		(duplicate_pad_numbers_are_jumpers no)
		(fp_line
			(start 0.7874 0.4064)
			(end -0.7874 0.4064)
			(stroke
				(width 0.1524)
				(type default)
			)
			(layer "F.SilkS")
		)
		(fp_line
			(start 0.7874 -0.4064)
			(end 0.7874 0.4064)
			(stroke
				(width 0.1524)
				(type default)
			)
			(layer "F.SilkS")
		)
		(fp_line
			(start -0.7874 0.4064)
			(end -0.7874 -0.4064)
			(stroke
				(width 0.1524)
				(type default)
			)
			(layer "F.SilkS")
		)
		(fp_line
			(start -0.7874 -0.4064)
			(end 0.7874 -0.4064)
			(stroke
				(width 0.1524)
				(type default)
			)
			(layer "F.SilkS")
		)
		(fp_line
			(start 0.67945 0.3048)
			(end 0.120396 0.3048)
			(stroke
				(width 0.1)
				(type default)
			)
			(layer "F.Fab")
		)
		(fp_line
			(start 0.67945 -0.3048)
			(end 0.67945 0.3048)
			(stroke
				(width 0.1)
				(type default)
			)
			(layer "F.Fab")
		)
		(fp_line
			(start 0.12065 -0.2794)
			(end 0.12065 -0.3048)
			(stroke
				(width 0.1)
				(type default)
			)
			(layer "F.Fab")
		)
		(fp_line
			(start 0.12065 -0.3048)
			(end 0.67945 -0.3048)
			(stroke
				(width 0.1)
				(type default)
			)
			(layer "F.Fab")
		)
		(fp_line
			(start 0.120396 0.3048)
			(end 0.120396 0.2794)
			(stroke
				(width 0.1)
				(type default)
			)
			(layer "F.Fab")
		)
		(fp_line
			(start 0.120396 0.2794)
			(end -0.12065 0.2794)
			(stroke
				(width 0.1)
				(type default)
			)
			(layer "F.Fab")
		)
		(fp_line
			(start -0.12065 0.3048)
			(end -0.67945 0.3048)
			(stroke
				(width 0.1)
				(type default)
			)
			(layer "F.Fab")
		)
		(fp_line
			(start -0.12065 0.2794)
			(end -0.12065 0.3048)
			(stroke
				(width 0.1)
				(type default)
			)
			(layer "F.Fab")
		)
		(fp_line
			(start -0.12065 -0.2794)
			(end 0.12065 -0.2794)
			(stroke
				(width 0.1)
				(type default)
			)
			(layer "F.Fab")
		)
		(fp_line
			(start -0.12065 -0.305054)
			(end -0.12065 -0.2794)
			(stroke
				(width 0.1)
				(type default)
			)
			(layer "F.Fab")
		)
		(fp_line
			(start -0.67945 0.3048)
			(end -0.67945 -0.305054)
			(stroke
				(width 0.1)
				(type default)
			)
			(layer "F.Fab")
		)
		(fp_line
			(start -0.67945 -0.305054)
			(end -0.12065 -0.305054)
			(stroke
				(width 0.1)
				(type default)
			)
			(layer "F.Fab")
		)
		(pad "1" smd circle
			(at -0.40005 0 180)
			(size 0 0)
			(layers "F.Cu" "F.Mask" "F.Paste")
			(net "P12V_OCP_CB_2")
		)
		(pad "2" smd circle
			(at 0.40005 0 180)
			(size 0 0)
			(layers "F.Cu" "F.Mask" "F.Paste")
			(net "GND")
		)
	)
	(footprint ""
		(layer "F.Cu")
		(at 166.42588 -436.971948)
		(property "Reference" "U253"
			(at -1.43256 -2.86385 0)
			(unlocked yes)
			(layer "F.SilkS")
			(effects
				(font
					(size 0.7874 0.5842)
					(thickness 0.1524)
				)
				(justify left)
			)
		)
		(property "Value" ""
			(at 0 0 0)
			(layer "F.Fab")
			(effects
				(font
					(size 1.27 1.27)
				)
			)
		)
		(duplicate_pad_numbers_are_jumpers no)
		(fp_line
			(start -1.3462 -1.100074)
			(end -0.670052 -1.100074)
			(stroke
				(width 0.1524)
				(type default)
			)
			(layer "F.SilkS")
		)
		(fp_line
			(start -1.3462 1.100074)
			(end -1.3462 -1.100074)
			(stroke
				(width 0.1524)
				(type default)
			)
			(layer "F.SilkS")
		)
		(fp_line
			(start -0.670052 -1.100074)
			(end 0 -0.381)
			(stroke
				(width 0.1524)
				(type default)
			)
			(layer "F.SilkS")
		)
		(fp_line
			(start 0 -0.381)
			(end 0.670052 -1.100074)
			(stroke
				(width 0.1524)
				(type default)
			)
			(layer "F.SilkS")
		)
		(fp_line
			(start 0.670052 -1.100074)
			(end 1.3462 -1.100074)
			(stroke
				(width 0.1524)
				(type default)
			)
			(layer "F.SilkS")
		)
		(fp_line
			(start 1.3462 -1.100074)
			(end 1.3462 1.100074)
			(stroke
				(width 0.1524)
				(type default)
			)
			(layer "F.SilkS")
		)
		(fp_line
			(start 1.3462 1.100074)
			(end -1.3462 1.100074)
			(stroke
				(width 0.1524)
				(type default)
			)
			(layer "F.SilkS")
		)
		(fp_poly
			(pts
				(xy -1.056894 -1.39446) (xy -1.437894 -2.15646) (xy -0.675894 -2.15646)
			)
			(stroke
				(width 0)
				(type default)
			)
			(fill yes)
			(layer "F.SilkS")
		)
		(fp_line
			(start -1.100074 -0.8001)
			(end -0.670052 -0.8001)
			(stroke
				(width 0.1)
				(type default)
			)
			(layer "F.Fab")
		)
		(fp_line
			(start -1.100074 0.8001)
			(end -1.100074 -0.8001)
			(stroke
				(width 0.1)
				(type default)
			)
			(layer "F.Fab")
		)
		(fp_line
			(start -0.670052 -1.100074)
			(end 0.670052 -1.100074)
			(stroke
				(width 0.1)
				(type default)
			)
			(layer "F.Fab")
		)
		(fp_line
			(start -0.670052 -0.8001)
			(end -0.670052 -1.100074)
			(stroke
				(width 0.1)
				(type default)
			)
			(layer "F.Fab")
		)
		(fp_line
			(start -0.670052 0.8001)
			(end -1.100074 0.8001)
			(stroke
				(width 0.1)
				(type default)
			)
			(layer "F.Fab")
		)
		(fp_line
			(start -0.670052 0.8001)
			(end -0.670052 -0.8001)
			(stroke
				(width 0.1)
				(type default)
			)
			(layer "F.Fab")
		)
		(fp_line
			(start -0.670052 1.100074)
			(end -0.670052 0.8001)
			(stroke
				(width 0.1)
				(type default)
			)
			(layer "F.Fab")
		)
		(fp_line
			(start 0.670052 -1.100074)
			(end 0.670052 -0.8001)
			(stroke
				(width 0.1)
				(type default)
			)
			(layer "F.Fab")
		)
		(fp_line
			(start 0.670052 -0.8001)
			(end 0.670052 0.8001)
			(stroke
				(width 0.1)
				(type default)
			)
			(layer "F.Fab")
		)
		(fp_line
			(start 0.670052 -0.8001)
			(end 1.100074 -0.8001)
			(stroke
				(width 0.1)
				(type default)
			)
			(layer "F.Fab")
		)
		(fp_line
			(start 0.670052 0.8001)
			(end 0.670052 1.100074)
			(stroke
				(width 0.1)
				(type default)
			)
			(layer "F.Fab")
		)
		(fp_line
			(start 0.670052 1.100074)
			(end -0.670052 1.100074)
			(stroke
				(width 0.1)
				(type default)
			)
			(layer "F.Fab")
		)
		(fp_line
			(start 1.100074 -0.8001)
			(end 1.100074 0.8001)
			(stroke
				(width 0.1)
				(type default)
			)
			(layer "F.Fab")
		)
		(fp_line
			(start 1.100074 0.8001)
			(end 0.670052 0.8001)
			(stroke
				(width 0.1)
				(type default)
			)
			(layer "F.Fab")
		)
		(fp_poly
			(pts
				(xy -1.524 -0.649986) (xy -2.286 -1.030986) (xy -2.286 -0.268986)
			)
			(stroke
				(width 0)
				(type default)
			)
			(fill yes)
			(layer "F.Fab")
		)
		(pad "1" smd rect
			(at -0.94996 -0.649986 270)
			(size 0.4064 0.508)
			(layers "F.Cu" "F.Mask" "F.Paste")
			(net "GPU_FPGA_BOOT_EN")
		)
		(pad "2" smd rect
			(at -0.94996 0 270)
			(size 0.4064 0.508)
			(layers "F.Cu" "F.Mask" "F.Paste")
			(net "GND")
		)
		(pad "3" smd rect
			(at -0.94996 0.649986 270)
			(size 0.4064 0.508)
			(layers "F.Cu" "F.Mask" "F.Paste")
			(net "GPU_BASE_STBY_EN")
		)
		(pad "4" smd rect
			(at 0.94996 0.649986 270)
			(size 0.4064 0.508)
			(layers "F.Cu" "F.Mask" "F.Paste")
			(net "GPU_BASE_STBY_EN_BUF_R")
		)
		(pad "5" smd rect
			(at 0.94996 0 270)
			(size 0.4064 0.508)
			(layers "F.Cu" "F.Mask" "F.Paste")
			(net "P3V3_AUX")
		)
		(pad "6" smd rect
			(at 0.94996 -0.649986 270)
			(size 0.4064 0.508)
			(layers "F.Cu" "F.Mask" "F.Paste")
			(net "GPU_FPGA_BOOT_EN_BUF_R")
		)
	)
)
